# S9S_MB_2U (Grand Teton) — schematic netlist excerpt (pin names and nets, part order shuffled) for the footprints in the layout excerpt that follows; sources: Cadence DE-HDL packaged netlist, KiCad conversion of 03242023_DA0F0TMBIJ0_F0T_Motherboard_J_brd_V01_OCP.brd

C1324  Q_CAP  0.1UF 25V 10% EMPTY  pkg 0402  page 208 : A = FM_CK440Q_DEV_25M_EN ; B = GND
C1237  Q_CAP  0.1UF 25V 10% X7R  pkg 0402  page 153 : A = P3V3_OCP_SFF ; B = GND

(kicad_pcb
	(version 20260206)
	(generator "pcbnew")
	(generator_version "10.0")
	(general
		(thickness 1.6)
		(legacy_teardrops no)
	)
	(paper "A4")
	(title_block
		(title "03242023_DA0F0TMBIJ0_F0T_Motherboard_J_brd_V01_OCP.brd")
		(comment 1 "Grand Teton / footprints 5641-5642 of 6105")
	)
	(layers
		(0 "F.Cu" signal "TOP")
		(4 "In1.Cu" signal "GND")
		(6 "In2.Cu" signal "IN1")
		(8 "In3.Cu" signal "GND1")
		(10 "In4.Cu" signal "IN2")
		(12 "In5.Cu" signal "GND2")
		(14 "In6.Cu" signal "IN3")
		(16 "In7.Cu" signal "GND3")
		(18 "In8.Cu" signal "VCC")
		(20 "In9.Cu" signal "VCC1")
		(22 "In10.Cu" signal "GND4")
		(24 "In11.Cu" signal "IN4")
		(26 "In12.Cu" signal "GND5")
		(28 "In13.Cu" signal "IN5")
		(30 "In14.Cu" signal "GND6")
		(32 "In15.Cu" signal "IN6")
		(34 "In16.Cu" signal "GND7")
		(2 "B.Cu" signal "BOTTOM")
		(9 "F.Adhes" user "F.Adhesive")
		(11 "B.Adhes" user "B.Adhesive")
		(13 "F.Paste" user "Package Geometry/Pastemask Top")
		(15 "B.Paste" user "Package Geometry/Pastemask Bottom")
		(5 "F.SilkS" user "Ref Des/Silkscreen Top")
		(7 "B.SilkS" user "Ref Des/Silkscreen Bottom")
		(1 "F.Mask" user "Board Geometry/Soldermask Top")
		(3 "B.Mask" user "Board Geometry/Soldermask Bottom")
		(17 "Dwgs.User" user "User.Drawings")
		(19 "Cmts.User" user "User.Comments")
		(21 "Eco1.User" user "User.Eco1")
		(23 "Eco2.User" user "User.Eco2")
		(25 "Edge.Cuts" user "Board Geometry/Outline")
		(27 "Margin" user)
		(31 "F.CrtYd" user "Package Geometry/Place Bound Top")
		(29 "B.CrtYd" user "Package Geometry/Place Bound Bottom")
		(35 "F.Fab" user "Ref Des/Assembly Top")
		(33 "B.Fab" user "Ref Des/Assembly Bottom")
	)
	(footprint ""
		(layer "B.Cu")
		(at 252.05563 -105.256584 -90)
		(property "Reference" "C1324"
			(at 0 0 90)
			(layer "B.SilkS")
			(hide yes)
			(effects
				(font
					(size 1.27 1.27)
				)
				(justify mirror)
			)
		)
		(property "Value" ""
			(at 0 0 90)
			(layer "B.Fab")
			(effects
				(font
					(size 1.27 1.27)
				)
				(justify mirror)
			)
		)
		(duplicate_pad_numbers_are_jumpers no)
		(fp_line
			(start -0.7874 0.4064)
			(end 0.7874 0.4064)
			(stroke
				(width 0.1524)
				(type default)
			)
			(layer "B.SilkS")
		)
		(fp_line
			(start 0.7874 0.4064)
			(end 0.7874 -0.4064)
			(stroke
				(width 0.1524)
				(type default)
			)
			(layer "B.SilkS")
		)
		(fp_line
			(start -0.7874 -0.4064)
			(end -0.7874 0.4064)
			(stroke
				(width 0.1524)
				(type default)
			)
			(layer "B.SilkS")
		)
		(fp_line
			(start 0.7874 -0.4064)
			(end -0.7874 -0.4064)
			(stroke
				(width 0.1524)
				(type default)
			)
			(layer "B.SilkS")
		)
		(fp_line
			(start -0.67945 0.3048)
			(end -0.120396 0.3048)
			(stroke
				(width 0.1)
				(type default)
			)
			(layer "B.Fab")
		)
		(fp_line
			(start -0.120396 0.3048)
			(end -0.120396 0.2794)
			(stroke
				(width 0.1)
				(type default)
			)
			(layer "B.Fab")
		)
		(fp_line
			(start 0.12065 0.3048)
			(end 0.67945 0.3048)
			(stroke
				(width 0.1)
				(type default)
			)
			(layer "B.Fab")
		)
		(fp_line
			(start 0.67945 0.3048)
			(end 0.67945 -0.305054)
			(stroke
				(width 0.1)
				(type default)
			)
			(layer "B.Fab")
		)
		(fp_line
			(start -0.120396 0.2794)
			(end 0.12065 0.2794)
			(stroke
				(width 0.1)
				(type default)
			)
			(layer "B.Fab")
		)
		(fp_line
			(start 0.12065 0.2794)
			(end 0.12065 0.3048)
			(stroke
				(width 0.1)
				(type default)
			)
			(layer "B.Fab")
		)
		(fp_line
			(start -0.12065 -0.2794)
			(end -0.12065 -0.3048)
			(stroke
				(width 0.1)
				(type default)
			)
			(layer "B.Fab")
		)
		(fp_line
			(start 0.12065 -0.2794)
			(end -0.12065 -0.2794)
			(stroke
				(width 0.1)
				(type default)
			)
			(layer "B.Fab")
		)
		(fp_line
			(start -0.67945 -0.3048)
			(end -0.67945 0.3048)
			(stroke
				(width 0.1)
				(type default)
			)
			(layer "B.Fab")
		)
		(fp_line
			(start -0.12065 -0.3048)
			(end -0.67945 -0.3048)
			(stroke
				(width 0.1)
				(type default)
			)
			(layer "B.Fab")
		)
		(fp_line
			(start 0.12065 -0.305054)
			(end 0.12065 -0.2794)
			(stroke
				(width 0.1)
				(type default)
			)
			(layer "B.Fab")
		)
		(fp_line
			(start 0.67945 -0.305054)
			(end 0.12065 -0.305054)
			(stroke
				(width 0.1)
				(type default)
			)
			(layer "B.Fab")
		)
		(pad "1" smd circle
			(at 0.40005 0 90)
			(size 0 0)
			(layers "B.Cu" "B.Mask" "B.Paste")
			(net "FM_CK440Q_DEV_25M_EN")
		)
		(pad "2" smd circle
			(at -0.40005 0 90)
			(size 0 0)
			(layers "B.Cu" "B.Mask" "B.Paste")
			(net "GND")
		)
	)
	(footprint ""
		(layer "B.Cu")
		(at 435.549802 -13.120116 180)
		(property "Reference" "C1237"
			(at 0 0 0)
			(layer "B.SilkS")
			(hide yes)
			(effects
				(font
					(size 1.27 1.27)
				)
				(justify mirror)
			)
		)
		(property "Value" ""
			(at 0 0 0)
			(layer "B.Fab")
			(effects
				(font
					(size 1.27 1.27)
				)
				(justify mirror)
			)
		)
		(duplicate_pad_numbers_are_jumpers no)
		(fp_line
			(start 0.7874 0.4064)
			(end 0.7874 -0.4064)
			(stroke
				(width 0.1524)
				(type default)
			)
			(layer "B.SilkS")
		)
		(fp_line
			(start 0.7874 -0.4064)
			(end -0.7874 -0.4064)
			(stroke
				(width 0.1524)
				(type default)
			)
			(layer "B.SilkS")
		)
		(fp_line
			(start -0.7874 0.4064)
			(end 0.7874 0.4064)
			(stroke
				(width 0.1524)
				(type default)
			)
			(layer "B.SilkS")
		)
		(fp_line
			(start -0.7874 -0.4064)
			(end -0.7874 0.4064)
			(stroke
				(width 0.1524)
				(type default)
			)
			(layer "B.SilkS")
		)
		(fp_line
			(start 0.67945 0.3048)
			(end 0.67945 -0.305054)
			(stroke
				(width 0.1)
				(type default)
			)
			(layer "B.Fab")
		)
		(fp_line
			(start 0.67945 -0.305054)
			(end 0.12065 -0.305054)
			(stroke
				(width 0.1)
				(type default)
			)
			(layer "B.Fab")
		)
		(fp_line
			(start 0.12065 0.3048)
			(end 0.67945 0.3048)
			(stroke
				(width 0.1)
				(type default)
			)
			(layer "B.Fab")
		)
		(fp_line
			(start 0.12065 0.2794)
			(end 0.12065 0.3048)
			(stroke
				(width 0.1)
				(type default)
			)
			(layer "B.Fab")
		)
		(fp_line
			(start 0.12065 -0.2794)
			(end -0.12065 -0.2794)
			(stroke
				(width 0.1)
				(type default)
			)
			(layer "B.Fab")
		)
		(fp_line
			(start 0.12065 -0.305054)
			(end 0.12065 -0.2794)
			(stroke
				(width 0.1)
				(type default)
			)
			(layer "B.Fab")
		)
		(fp_line
			(start -0.120396 0.3048)
			(end -0.120396 0.2794)
			(stroke
				(width 0.1)
				(type default)
			)
			(layer "B.Fab")
		)
		(fp_line
			(start -0.120396 0.2794)
			(end 0.12065 0.2794)
			(stroke
				(width 0.1)
				(type default)
			)
			(layer "B.Fab")
		)
		(fp_line
			(start -0.12065 -0.2794)
			(end -0.12065 -0.3048)
			(stroke
				(width 0.1)
				(type default)
			)
			(layer "B.Fab")
		)
		(fp_line
			(start -0.12065 -0.3048)
			(end -0.67945 -0.3048)
			(stroke
				(width 0.1)
				(type default)
			)
			(layer "B.Fab")
		)
		(fp_line
			(start -0.67945 0.3048)
			(end -0.120396 0.3048)
			(stroke
				(width 0.1)
				(type default)
			)
			(layer "B.Fab")
		)
		(fp_line
			(start -0.67945 -0.3048)
			(end -0.67945 0.3048)
			(stroke
				(width 0.1)
				(type default)
			)
			(layer "B.Fab")
		)
		(pad "1" smd circle
			(at 0.40005 0)
			(size 0 0)
			(layers "B.Cu" "B.Mask" "B.Paste")
			(net "P3V3_OCP_SFF")
		)
		(pad "2" smd circle
			(at -0.40005 0)
			(size 0 0)
			(layers "B.Cu" "B.Mask" "B.Paste")
			(net "GND")
		)
	)
)
